FILE_TYPE = CONNECTIVITY;
{Allegro Design Entry HDL 16.6-p007 (v16-6-112F) 10/10/2012}
"PAGE_NUMBER" = 245;
0"NC";
1"P3E_CPU0_PE2_SS_C_TXP<15:8>";
2"P3E_CPU0_PE2_SS_C_TXN<15:8>";
3"P3E_CPU0_PE2_SS_RXP<15:8>";
4"P3E_CPU0_PE2_SS_RXN<15:8>";
5"GND\g";
6"GND\g";
7"GND\g";
8"GND\g"BOM_COST"TBD"ROOM"TBD"CDS_PHYS_NET_NAME"GND"VOLTAGE"0";
9"P3V3_STBY\g";
10"GND\g";
11"GND\g";
12"P3V3_STBY\g";
13"P3E_CPU0_PE2_SS_C_TXN<11>";
14"JTAG_RISER_TRST";
15"JTAG_PLD_TCK_MUX";
16"JTAG_BMC_TRST_N";
17"JTAG_RISER_TDI";
18"P3E_CPU0_PE2_SS_C_TXP<15>";
19"P3E_CPU0_PE2_SS_C_TXN<15>";
20"JTAG_RISER_TDO";
21"USB2_P02_DN";
22"P3E_CPU0_PE2_SS_C_TXN<14>";
23"P3E_CPU0_PE2_SS_RXN<11>";
24"P3E_CPU0_PE2_SS_RXP<11>";
25"P3E_CPU0_PE2_SS_RXN<12>";
26"P3E_CPU0_PE2_SS_RXP<12>";
27"P3E_CPU0_PE2_SS_RXP<13>";
28"P3E_CPU0_PE2_SS_RXN<14>";
29"P3E_CPU0_PE2_SS_RXP<14>";
30"P3E_CPU0_PE2_SS_RXN<15>";
31"P3E_CPU0_PE2_SS_RXP<15>";
32"JTAG_RISER_TMS";
33"P3E_CPU0_PE2_SS_RXN<13>";
34"P3E_CPU0_PE2_SS_C_TXN<12>";
35"JTAG_RISER_TDO_R";
36"JTAG_RISER_TDI_R";
37"USB2_P02_DP";
38"JTAG_RISER_N";
39"JTAG_PLD_TDO";
40"JTAG_PLD_TMS_MUX";
41"JTAG_RISER_TDI_R";
42"P3E_CPU0_PE2_SS_C_TXP<14>";
43"P3E_CPU0_PE2_SS_C_TXP<12>";
44"P3E_CPU0_PE2_SS_C_TXN<13>";
45"JTAG_RISER_TCK";
46"P3E_CPU0_PE2_SS_C_TXP<13>";
47"P3E_CPU0_PE2_SS_RXN<10>";
48"P3E_CPU0_PE2_SS_RXP<9>";
49"P3E_CPU0_PE2_SS_RXP<8>"CDS_PHYS_NET_NAME"P3E_CPU0_PE2_SS_RXP<8>";
50"P3E_CPU0_PE2_SS_RXN<8>"CDS_PHYS_NET_NAME"P3E_CPU0_PE2_SS_RXN<8>";
51"P3E_CPU0_PE2_SS_RXN<9>";
52"P3E_CPU0_PE2_SS_RXP<10>";
53"P3E_CPU0_PE2_SS_C_TXP<11>";
54"P3E_CPU0_PE2_SS_C_TXP<10>";
55"P3E_CPU0_PE2_SS_C_TXN<10>";
56"P3E_CPU0_PE2_SS_C_TXN<9>";
57"P3E_CPU0_PE2_SS_C_TXN<8>";
58"P3E_CPU0_PE2_SS_C_TXP<9>";
59"P3E_CPU0_PE2_SS_C_TXP<8>";
60"JTAG_RISER_TDO_R";
61"JTAG_PLD_TDO_MUX_R";
%"TAP"
"1","(-5900,3925)","2","mstr_standard","I10";
;
HDL_TAP"TRUE"
BODY_TYPE"PLUMBING"
CDS_LIB"mstr_standard";
"B \NAC \NWC"2;
"S \NAC"
BN"11"13;
%"TAP"
"1","(-5900,4125)","2","mstr_standard","I11";
;
HDL_TAP"TRUE"
BODY_TYPE"PLUMBING"
CDS_LIB"mstr_standard";
"B \NAC \NWC"2;
"S \NAC"
BN"10"55;
%"TAP"
"1","(-5900,4275)","2","mstr_standard","I12";
;
HDL_TAP"TRUE"
BODY_TYPE"PLUMBING"
CDS_LIB"mstr_standard";
"B \NAC \NWC"2;
"S \NAC"
BN"9"56;
%"TAP"
"1","(-5275,3525)","2","mstr_standard","I13";
;
HDL_TAP"TRUE"
BODY_TYPE"PLUMBING"
CDS_LIB"mstr_standard";
"B \NAC \NWC"1;
"S \NAC"
BN"14"42;
%"TAP"
"1","(-5275,3775)","2","mstr_standard","I14";
;
HDL_TAP"TRUE"
BODY_TYPE"PLUMBING"
CDS_LIB"mstr_standard";
"B \NAC \NWC"1;
"S \NAC"
BN"12"43;
%"TAP"
"1","(-5275,3625)","2","mstr_standard","I15";
;
HDL_TAP"TRUE"
BODY_TYPE"PLUMBING"
CDS_LIB"mstr_standard";
"B \NAC \NWC"1;
"S \NAC"
BN"13"46;
%"TAP"
"1","(-5275,3975)","2","mstr_standard","I16";
;
HDL_TAP"TRUE"
BODY_TYPE"PLUMBING"
CDS_LIB"mstr_standard";
"B \NAC \NWC"1;
"S \NAC"
BN"11"53;
%"TAP"
"1","(-5275,4075)","2","mstr_standard","I17";
;
HDL_TAP"TRUE"
BODY_TYPE"PLUMBING"
CDS_LIB"mstr_standard";
"B \NAC \NWC"1;
"S \NAC"
BN"10"54;
%"TAP"
"1","(-5275,4225)","2","mstr_standard","I18";
;
HDL_TAP"TRUE"
BODY_TYPE"PLUMBING"
CDS_LIB"mstr_standard";
"B \NAC \NWC"1;
"S \NAC"
BN"9"58;
%"GND"
"1","(-4725,2825)","0","mstr_symbols","I19";
;
HDL_POWER"GND"
BODY_TYPE"PLUMBING"
ROOM"PVPP_KLM_VR"
SIZE"1B"
VOLTAGE"0"
BOM_COST"PVPP_KLM_VR"
CDS_LIB"mstr_symbols";
"A\NAC"5;
%"GND"
"1","(-4275,2625)","0","mstr_symbols","I20";
;
HDL_POWER"GND"
BODY_TYPE"PLUMBING"
BOM_COST"PVPP_KLM_VR"
VOLTAGE"0"
SIZE"1B"
ROOM"PVPP_KLM_VR"
CDS_LIB"mstr_symbols";
"A\NAC"6;
%"GND"
"1","(-4425,4575)","0","mstr_symbols","I25";
;
HDL_POWER"GND"
BODY_TYPE"PLUMBING"
CDS_LIB"mstr_symbols"
ROOM"PVPP_KLM_VR"
SIZE"1B"
VOLTAGE"0"
BOM_COST"PVPP_KLM_VR";
"A\NAC"7;
%"GND"
"1","(-3375,2625)","0","mstr_symbols","I27";
;
HDL_POWER"GND"
BODY_TYPE"PLUMBING"
BOM_COST"PVPP_KLM_VR"
VOLTAGE"0"
SIZE"1B"
ROOM"PVPP_KLM_VR"
CDS_LIB"mstr_symbols";
"A\NAC"8;
%"TAP"
"6","(-2475,3325)","2","mstr_standard","I29";
;
HDL_TAP"TRUE"
BODY_TYPE"PLUMBING"
CDS_LIB"mstr_standard";
"B \NAC \NWC"4;
"S \NAC"
BN"15"30;
%"TAP"
"6","(-2275,3275)","2","mstr_standard","I30";
;
HDL_TAP"TRUE"
BODY_TYPE"PLUMBING"
CDS_LIB"mstr_standard";
"B \NAC \NWC"3;
"S \NAC"
BN"15"31;
%"TAP"
"6","(-2475,3575)","2","mstr_standard","I31";
;
HDL_TAP"TRUE"
BODY_TYPE"PLUMBING"
CDS_LIB"mstr_standard";
"B \NAC \NWC"4;
"S \NAC"
BN"13"33;
%"TAP"
"6","(-2475,3475)","2","mstr_standard","I32";
;
HDL_TAP"TRUE"
BODY_TYPE"PLUMBING"
CDS_LIB"mstr_standard";
"B \NAC \NWC"4;
"S \NAC"
BN"14"28;
%"TAP"
"6","(-2475,3775)","2","mstr_standard","I33";
;
HDL_TAP"TRUE"
BODY_TYPE"PLUMBING"
CDS_LIB"mstr_standard";
"B \NAC \NWC"4;
"S \NAC"
BN"12"25;
%"TAP"
"6","(-2475,3925)","2","mstr_standard","I34";
;
HDL_TAP"TRUE"
BODY_TYPE"PLUMBING"
CDS_LIB"mstr_standard";
"B \NAC \NWC"4;
"S \NAC"
BN"11"23;
%"TAP"
"6","(-2475,4075)","2","mstr_standard","I35";
;
HDL_TAP"TRUE"
BODY_TYPE"PLUMBING"
CDS_LIB"mstr_standard";
"B \NAC \NWC"4;
"S \NAC"
BN"10"47;
%"TAP"
"6","(-2475,4225)","2","mstr_standard","I36";
;
HDL_TAP"TRUE"
BODY_TYPE"PLUMBING"
CDS_LIB"mstr_standard";
"B \NAC \NWC"4;
"S \NAC"
BN"9"51;
%"TAP"
"6","(-2275,3425)","2","mstr_standard","I37";
;
HDL_TAP"TRUE"
BODY_TYPE"PLUMBING"
CDS_LIB"mstr_standard";
"B \NAC \NWC"3;
"S \NAC"
BN"14"29;
%"TAP"
"6","(-2275,3725)","2","mstr_standard","I38";
;
HDL_TAP"TRUE"
BODY_TYPE"PLUMBING"
CDS_LIB"mstr_standard";
"B \NAC \NWC"3;
"S \NAC"
BN"12"26;
%"TAP"
"6","(-2275,3625)","2","mstr_standard","I39";
;
HDL_TAP"TRUE"
BODY_TYPE"PLUMBING"
CDS_LIB"mstr_standard";
"B \NAC \NWC"3;
"S \NAC"
BN"13"27;
%"TAP"
"6","(-2275,4025)","2","mstr_standard","I40";
;
HDL_TAP"TRUE"
BODY_TYPE"PLUMBING"
CDS_LIB"mstr_standard";
"B \NAC \NWC"3;
"S \NAC"
BN"10"52;
%"TAP"
"6","(-2275,3875)","2","mstr_standard","I41";
;
HDL_TAP"TRUE"
BODY_TYPE"PLUMBING"
CDS_LIB"mstr_standard";
"B \NAC \NWC"3;
"S \NAC"
BN"11"24;
%"TAP"
"6","(-2275,4175)","2","mstr_standard","I42";
;
HDL_TAP"TRUE"
BODY_TYPE"PLUMBING"
CDS_LIB"mstr_standard";
"B \NAC \NWC"3;
"S \NAC"
BN"9"48;
%"TAP"
"6","(-2275,4325)","2","mstr_standard","I43";
;
HDL_TAP"TRUE"
BODY_TYPE"PLUMBING"
CDS_LIB"mstr_standard";
"B \NAC \NWC"3;
"S \NAC"
BN"8"49;
%"TAP"
"6","(-2475,4375)","2","mstr_standard","I44";
;
HDL_TAP"TRUE"
BODY_TYPE"PLUMBING"
CDS_LIB"mstr_standard";
"B \NAC \NWC"4;
"S \NAC"
BN"8"50;
%"SMC-CONN60A-22-GP"
"1","(-4000,3775)","0","w_hdl","I48";
;
LOCATION"CONX8"
VALUE"SMC-CONN60A-22-GP"
CDS_SEC"1"
$SEC"1"
CDS_LOCATION"CONX8"
CDS_LMAN_SYM_OUTLINE"-100,900,100,-900"
CDS_LIB"w_hdl"
PART_NUMBER"020.C0082.0060"
PACK_TYPE"CONN-G7";
"PTH2"
$PN"PTH2"6;
"PTH1"
$PN"PTH1"7;
"NP2"
$PN"NP2"0;
"NP1"
$PN"NP1"0;
"60"
$PN"60"14;
"58"
$PN"58"8;
"56"
$PN"56"45;
"54"
$PN"54"32;
"52"
$PN"52"8;
"50"
$PN"50"31;
"48"
$PN"48"30;
"46"
$PN"46"8;
"44"
$PN"44"29;
"42"
$PN"42"28;
"40"
$PN"40"8;
"38"
$PN"38"33;
"36"
$PN"36"27;
"34"
$PN"34"8;
"32"
$PN"32"26;
"30"
$PN"30"25;
"28"
$PN"28"8;
"26"
$PN"26"24;
"24"
$PN"24"23;
"22"
$PN"22"8;
"20"
$PN"20"52;
"18"
$PN"18"47;
"16"
$PN"16"8;
"14"
$PN"14"48;
"12"
$PN"12"51;
"10"
$PN"10"8;
"59"
$PN"59"37;
"57"
$PN"57"21;
"55"
$PN"55"5;
"53"
$PN"53"20;
"51"
$PN"51"17;
"49"
$PN"49"5;
"47"
$PN"47"18;
"45"
$PN"45"19;
"43"
$PN"43"5;
"41"
$PN"41"22;
"39"
$PN"39"42;
"37"
$PN"37"5;
"35"
$PN"35"46;
"33"
$PN"33"44;
"31"
$PN"31"5;
"29"
$PN"29"43;
"27"
$PN"27"34;
"25"
$PN"25"5;
"23"
$PN"23"13;
"21"
$PN"21"53;
"19"
$PN"19"5;
"17"
$PN"17"54;
"15"
$PN"15"55;
"13"
$PN"13"5;
"11"
$PN"11"58;
"9"
$PN"9"56;
"8"
$PN"8"49;
"6"
$PN"6"50;
"4"
$PN"4"8;
"2"
$PN"2"0;
"7"
$PN"7"5;
"5"
$PN"5"59;
"3"
$PN"3"57;
"1"
$PN"1"5;
%"TAP"
"1","(-5275,3325)","2","mstr_standard","I5";
;
HDL_TAP"TRUE"
BODY_TYPE"PLUMBING"
CDS_LIB"mstr_standard";
"B \NAC \NWC"1;
"S \NAC"
BN"15"18;
%"TAP"
"1","(-5900,4425)","2","mstr_standard","I52";
;
HDL_TAP"TRUE"
BODY_TYPE"PLUMBING"
CDS_LIB"mstr_standard";
"B \NAC \NWC"2;
"S \NAC"
BN"8"57;
%"TAP"
"1","(-5275,4375)","2","mstr_standard","I53";
;
HDL_TAP"TRUE"
BODY_TYPE"PLUMBING"
CDS_LIB"mstr_standard";
"B \NAC \NWC"1;
"S \NAC"
BN"8"59;
%"RES"
"1","(-2700,3175)","0","mstr_discrete","I56";
;
CDS_SEC"1"
TOLERANCE"5%"
PACK_TYPE"0402"
WATTAGE"1/16W"
MATERIAL"CHIP"
PART_NUMBER"G21497-005"
VALUE"0.0"
LOCATION"R8W10"
SEC"1"
SEC_TYPE"0402"
ROOM"BMC_DEBUG_HEADER"
BOM_COST"DEBUG"
CDS_LIB"mstr_discrete"
CDS_LOCATION"R8W10";
"B"
$PN"2"40;
"A"
$PN"1"32;
%"RES"
"1","(-2700,3125)","0","mstr_discrete","I57";
;
CDS_SEC"1"
VALUE"0.0"
PACK_TYPE"0402"
PART_NUMBER"G21497-005"
MATERIAL"CHIP"
WATTAGE"1/16W"
TOLERANCE"5%"
LOCATION"R8W11"
CDS_LIB"mstr_discrete"
BOM_COST"DEBUG"
ROOM"BMC_DEBUG_HEADER"
SEC_TYPE"0402"
SEC"1"
CDS_LOCATION"R8W11";
"B"
$PN"2"15;
"A"
$PN"1"45;
%"RES"
"1","(-2700,3025)","0","mstr_discrete","I58";
;
CDS_SEC"1"
LOCATION"R8W12"
PART_NUMBER"G21497-005"
MATERIAL"CHIP"
VALUE"0.0"
WATTAGE"1/16W"
PACK_TYPE"0402"
TOLERANCE"5%"
SEC"1"
SEC_TYPE"0402"
ROOM"BMC_DEBUG_HEADER"
BOM_COST"DEBUG"
CDS_LIB"mstr_discrete"
CDS_LOCATION"R8W12";
"B"
$PN"2"16;
"A"
$PN"1"14;
%"RES"
"1","(-6500,3225)","0","mstr_discrete","I59";
;
CDS_SEC"1"
VALUE"0.0"
LOCATION"R8W13"
PACK_TYPE"0402"
MATERIAL"CHIP"
WATTAGE"1/16W"
TOLERANCE"5%"
PART_NUMBER"G21497-005"
CDS_LIB"mstr_discrete"
BOM_COST"DEBUG"
ROOM"BMC_DEBUG_HEADER"
SEC_TYPE"0402"
SEC"1"
CDS_LOCATION"R8W13";
"B"
$PN"2"17;
"A"
$PN"1"36;
%"TAP"
"1","(-5900,3375)","2","mstr_standard","I6";
;
HDL_TAP"TRUE"
BODY_TYPE"PLUMBING"
CDS_LIB"mstr_standard";
"B \NAC \NWC"2;
"S \NAC"
BN"15"19;
%"RES"
"1","(-6500,3175)","0","mstr_discrete","I60";
;
CDS_SEC"1"
PACK_TYPE"0402"
VALUE"0.0"
LOCATION"R8W14"
MATERIAL"CHIP"
WATTAGE"1/16W"
TOLERANCE"5%"
PART_NUMBER"G21497-005"
SEC"1"
SEC_TYPE"0402"
ROOM"BMC_DEBUG_HEADER"
BOM_COST"DEBUG"
CDS_LIB"mstr_discrete"
CDS_LOCATION"R8W14";
"B"
$PN"2"20;
"A"
$PN"1"35;
%"74CBTLV1G125"
"1","(-3900,2000)","0","mstr_ttl","I64";
;
CDS_SEC"1"
CDS_LOCATION"U8W1"
PART_NUMBER"C88177-001"
POWER_GROUP"VCC=P3V3_STBY;GND=GND;"
LOCATION"U8W1"
MATERIAL"IC"
PACK_TYPE"SMLF"
SEC_TYPE"SMLF"
CDS_LIB"mstr_ttl"
BOM_COST"DEBUG"
SEC"1"
ROOM"DEBUG";
"OE_N \B"
$PN"1"38;
"B"
$PN"4"41;
"A"
$PN"2"39;
%"NC7SB3157"
"1","(-5950,1500)","2","mstr_analog","I66";
;
CDS_LOCATION"U8W2"
PART_NUMBER"C99406-001"
MATERIAL"IC"
PACK_TYPE"SMLF"
LOCATION"U8W2"
BOM_COST"DEBUG"
CDS_LIB"mstr_analog"
CDS_SEC"1"
$SEC"1"
ROOM"DEBUG";
"GND"
$PN"2"10;
"A"
$PN"4"61;
"VCC"
$PN"5"9;
"B1"
$PN"1"39;
"B0"
$PN"3"60;
"S"
$PN"6"38;
%"P3V3_STBY"
"1","(-5850,1100)","0","mstr_symbols","I67";
;
HDL_POWER"P3V3_STBY"
BODY_TYPE"PLUMBING"
CDS_LIB"mstr_symbols"
SIZE"1B"
VOLTAGE"+3.3V";
"G\NAC"9;
%"TAP"
"1","(-5900,3475)","2","mstr_standard","I7";
;
HDL_TAP"TRUE"
BODY_TYPE"PLUMBING"
CDS_LIB"mstr_standard";
"B \NAC \NWC"2;
"S \NAC"
BN"14"22;
%"CAP_A"
"1","(-5450,825)","2","dev_discrete","I71";
;
CDS_LOCATION"C8W6"
PACK_TYPE"0402V"
PART_NUMBER"A36096-045"
TOLERANCE"10%"
VALUE"0.01UF"
MATERIAL"X7R"
VOLTAGE"25V"
LOCATION"C8W6"
ROOM"DEBUG"
SEC"1"
SEC_TYPE"0402V"
CDS_SEC"1"
CDS_LIB"dev_discrete"
BOM_COST"DEBUG";
"B"
$PN"2"11;
"A"
$PN"1"9;
%"GND"
"1","(-6375,1275)","0","mstr_symbols","I72";
;
VOLTAGE"0.0V"
BOM_COST"DEBUG"
CDS_LIB"mstr_symbols"
SIZE"1B"
ROOM"CPU_JTAG_DEBUG"
BODY_TYPE"PLUMBING"
HDL_POWER"GND";
"A\NAC"10;
%"CAP_A"
"1","(-5850,825)","2","dev_discrete","I74";
;
CDS_LOCATION"C8W5"
MATERIAL"X6S"
VOLTAGE"6.3V"
PACK_TYPE"0402V"
TOLERANCE"10%"
VALUE"1.0UF"
PART_NUMBER"D97712-004"
LOCATION"C8W5"
ROOM"DEBUG"
$SEC"1"
CDS_SEC"1"
CDS_LIB"dev_discrete"
BOM_COST"DEBUG";
"B"
$PN"2"11;
"A"
$PN"1"9;
%"GND"
"1","(-5850,475)","0","mstr_symbols","I75";
;
HDL_POWER"GND"
BODY_TYPE"PLUMBING"
ROOM"CPU_JTAG_DEBUG"
SIZE"1B"
CDS_LIB"mstr_symbols"
BOM_COST"DEBUG"
VOLTAGE"0.0V";
"A\NAC"11;
%"RES"
"2","(-5500,2150)","0","mstr_discrete","I78";
;
CDS_SEC"1"
TOLERANCE"1%"
WATTAGE"1/16W"
PART_NUMBER"G21796-072"
LOCATION"R8W15"
PACK_TYPE"0402"
VALUE"4.75K"
MATERIAL"CHIP"
SEC"1"
SEC_TYPE"0402"
BOM_COST"SM_CONTROLLER"
CDS_LIB"mstr_discrete"
ROOM"BMC_MISC"
CDS_LOCATION"R8W15";
"A"
$PN"1"12;
"B"
$PN"2"38;
%"P3V3_STBY"
"1","(-5500,2350)","0","mstr_symbols","I79";
;
VOLTAGE"3.3V"
CDS_LIB"mstr_symbols"
SIZE"1B"
BODY_TYPE"PLUMBING"
HDL_POWER"P3V3_STBY";
"G\NAC"12;
%"TAP"
"1","(-5900,3825)","2","mstr_standard","I8";
;
HDL_TAP"TRUE"
BODY_TYPE"PLUMBING"
CDS_LIB"mstr_standard";
"B \NAC \NWC"2;
"S \NAC"
BN"12"34;
%"TAP"
"1","(-5900,3675)","2","mstr_standard","I9";
;
HDL_TAP"TRUE"
BODY_TYPE"PLUMBING"
CDS_LIB"mstr_standard";
"B \NAC \NWC"2;
"S \NAC"
BN"13"44;
END.
